(kicad_pcb
	(version 20260206)
	(generator "pcbnew")
	(generator_version "10.0")
	(general
		(thickness 1.6)
		(legacy_teardrops no)
	)
	(paper "A4")
	(title_block
		(title "04192023_DAF0TMB3IC0_F0TG_MB_C_brd_V02_OCP.brd")
		(comment 1 "Grand Teton / footprints 3509-3516 of 8354")
	)
	(layers
		(0 "F.Cu" signal "TOP")
		(4 "In1.Cu" signal "GND")
		(6 "In2.Cu" signal "IN1")
		(8 "In3.Cu" signal "GND1")
		(10 "In4.Cu" signal "IN2")
		(12 "In5.Cu" signal "GND2")
		(14 "In6.Cu" signal "IN3")
		(16 "In7.Cu" signal "GND3")
		(18 "In8.Cu" signal "VCC")
		(20 "In9.Cu" signal "VCC1")
		(22 "In10.Cu" signal "GND4")
		(24 "In11.Cu" signal "IN4")
		(26 "In12.Cu" signal "GND5")
		(28 "In13.Cu" signal "IN5")
		(30 "In14.Cu" signal "GND6")
		(32 "In15.Cu" signal "IN6")
		(34 "In16.Cu" signal "GND7")
		(2 "B.Cu" signal "BOTTOM")
		(9 "F.Adhes" user "F.Adhesive")
		(11 "B.Adhes" user "B.Adhesive")
		(13 "F.Paste" user "Package Geometry/Pastemask Top")
		(15 "B.Paste" user "Package Geometry/Pastemask Bottom")
		(5 "F.SilkS" user "Ref Des/Silkscreen Top")
		(7 "B.SilkS" user "Ref Des/Silkscreen Bottom")
		(1 "F.Mask" user "Board Geometry/Soldermask Top")
		(3 "B.Mask" user "Board Geometry/Soldermask Bottom")
		(17 "Dwgs.User" user "User.Drawings")
		(19 "Cmts.User" user "User.Comments")
		(21 "Eco1.User" user "User.Eco1")
		(23 "Eco2.User" user "User.Eco2")
		(25 "Edge.Cuts" user "Board Geometry/Outline")
		(27 "Margin" user)
		(31 "F.CrtYd" user "Package Geometry/Place Bound Top")
		(29 "B.CrtYd" user "Package Geometry/Place Bound Bottom")
		(35 "F.Fab" user "Ref Des/Assembly Top")
		(33 "B.Fab" user "Ref Des/Assembly Bottom")
	)
	(footprint ""
		(layer "F.Cu")
		(at 229.87 -285.64713 180)
		(property "Reference" "PC6903"
			(at 0 0 180)
			(layer "F.SilkS")
			(hide yes)
			(effects
				(font
					(size 1.27 1.27)
				)
			)
		)
		(property "Value" ""
			(at 0 0 180)
			(layer "F.Fab")
			(effects
				(font
					(size 1.27 1.27)
				)
			)
		)
		(duplicate_pad_numbers_are_jumpers no)
		(fp_line
			(start 1.524 0.762)
			(end -1.524 0.762)
			(stroke
				(width 0.1524)
				(type default)
			)
			(layer "F.SilkS")
		)
		(fp_line
			(start 1.524 -0.762)
			(end 1.524 0.762)
			(stroke
				(width 0.1524)
				(type default)
			)
			(layer "F.SilkS")
		)
		(fp_line
			(start -1.524 0.762)
			(end -1.524 -0.762)
			(stroke
				(width 0.1524)
				(type default)
			)
			(layer "F.SilkS")
		)
		(fp_line
			(start -1.524 -0.762)
			(end 1.524 -0.762)
			(stroke
				(width 0.1524)
				(type default)
			)
			(layer "F.SilkS")
		)
		(fp_line
			(start 1.1049 0.724916)
			(end 1.1049 -0.724916)
			(stroke
				(width 0.1)
				(type default)
			)
			(layer "F.Fab")
		)
		(fp_line
			(start 1.1049 -0.724916)
			(end -1.1049 -0.724916)
			(stroke
				(width 0.1)
				(type default)
			)
			(layer "F.Fab")
		)
		(fp_line
			(start -1.1049 0.724916)
			(end 1.1049 0.724916)
			(stroke
				(width 0.1)
				(type default)
			)
			(layer "F.Fab")
		)
		(fp_line
			(start -1.1049 -0.724916)
			(end -1.1049 0.724916)
			(stroke
				(width 0.1)
				(type default)
			)
			(layer "F.Fab")
		)
		(pad "1" smd rect
			(at -0.889 0)
			(size 1.016 1.27)
			(layers "F.Cu" "F.Mask" "F.Paste")
			(net "SW_P12V_AUX_P1V8_RETIMER_CPU1_FLT")
		)
		(pad "2" smd rect
			(at 0.889 0)
			(size 1.016 1.27)
			(layers "F.Cu" "F.Mask" "F.Paste")
			(net "GND")
		)
	)
	(footprint ""
		(layer "F.Cu")
		(at 312.958226 -416.899344 -90)
		(property "Reference" "C6508"
			(at 0 0 270)
			(layer "F.SilkS")
			(hide yes)
			(effects
				(font
					(size 1.27 1.27)
				)
			)
		)
		(property "Value" ""
			(at 0 0 270)
			(layer "F.Fab")
			(effects
				(font
					(size 1.27 1.27)
				)
			)
		)
		(duplicate_pad_numbers_are_jumpers no)
		(fp_line
			(start -0.299974 0.150114)
			(end -0.299974 -0.150114)
			(stroke
				(width 0.1)
				(type default)
			)
			(layer "F.Fab")
		)
		(fp_line
			(start 0.299974 0.150114)
			(end -0.299974 0.150114)
			(stroke
				(width 0.1)
				(type default)
			)
			(layer "F.Fab")
		)
		(fp_line
			(start -0.299974 -0.150114)
			(end 0.299974 -0.150114)
			(stroke
				(width 0.1)
				(type default)
			)
			(layer "F.Fab")
		)
		(fp_line
			(start 0.299974 -0.150114)
			(end 0.299974 0.150114)
			(stroke
				(width 0.1)
				(type default)
			)
			(layer "F.Fab")
		)
		(pad "1" smd rect
			(at -0.2667 0 270)
			(size 0.3048 0.381)
			(layers "F.Cu" "F.Mask" "F.Paste")
			(net "P5E_CPU0_P0_TX_BUF_C_DN<3>")
		)
		(pad "2" smd rect
			(at 0.2667 0 270)
			(size 0.3048 0.381)
			(layers "F.Cu" "F.Mask" "F.Paste")
			(net "P5E_CPU0_P0_TX_BUF_DN<3>")
		)
	)
	(footprint ""
		(layer "F.Cu")
		(at 329.686412 -40.00373)
		(property "Reference" "L15"
			(at 0 0 0)
			(layer "F.SilkS")
			(hide yes)
			(effects
				(font
					(size 1.27 1.27)
				)
			)
		)
		(property "Value" ""
			(at 0 0 0)
			(layer "F.Fab")
			(effects
				(font
					(size 1.27 1.27)
				)
			)
		)
		(duplicate_pad_numbers_are_jumpers no)
		(fp_line
			(start -1.27 -0.5842)
			(end 1.27 -0.5842)
			(stroke
				(width 0.1524)
				(type default)
			)
			(layer "F.SilkS")
		)
		(fp_line
			(start -1.27 -0.5588)
			(end -1.27 -0.5842)
			(stroke
				(width 0.1524)
				(type default)
			)
			(layer "F.SilkS")
		)
		(fp_line
			(start -1.27 0.5842)
			(end -1.27 -0.5842)
			(stroke
				(width 0.1524)
				(type default)
			)
			(layer "F.SilkS")
		)
		(fp_line
			(start 1.27 0.5842)
			(end -1.27 0.5842)
			(stroke
				(width 0.1524)
				(type default)
			)
			(layer "F.SilkS")
		)
		(fp_line
			(start 1.27 0.5842)
			(end 1.27 -0.5842)
			(stroke
				(width 0.1524)
				(type default)
			)
			(layer "F.SilkS")
		)
		(fp_line
			(start -1.194308 -0.406654)
			(end -0.9144 -0.406654)
			(stroke
				(width 0.1)
				(type default)
			)
			(layer "F.Fab")
		)
		(fp_line
			(start -1.194308 0.406654)
			(end -1.194308 -0.406654)
			(stroke
				(width 0.1)
				(type default)
			)
			(layer "F.Fab")
		)
		(fp_line
			(start -0.9144 -0.508)
			(end 0.9144 -0.508)
			(stroke
				(width 0.1)
				(type default)
			)
			(layer "F.Fab")
		)
		(fp_line
			(start -0.9144 -0.406654)
			(end -0.9144 -0.508)
			(stroke
				(width 0.1)
				(type default)
			)
			(layer "F.Fab")
		)
		(fp_line
			(start -0.9144 0.406654)
			(end -1.194308 0.406654)
			(stroke
				(width 0.1)
				(type default)
			)
			(layer "F.Fab")
		)
		(fp_line
			(start -0.9144 0.508)
			(end -0.9144 0.406654)
			(stroke
				(width 0.1)
				(type default)
			)
			(layer "F.Fab")
		)
		(fp_line
			(start 0.9144 -0.508)
			(end 0.9144 -0.406654)
			(stroke
				(width 0.1)
				(type default)
			)
			(layer "F.Fab")
		)
		(fp_line
			(start 0.9144 -0.406654)
			(end 1.1938 -0.406654)
			(stroke
				(width 0.1)
				(type default)
			)
			(layer "F.Fab")
		)
		(fp_line
			(start 0.9144 0.4064)
			(end 0.9144 0.508)
			(stroke
				(width 0.1)
				(type default)
			)
			(layer "F.Fab")
		)
		(fp_line
			(start 0.9144 0.508)
			(end -0.9144 0.508)
			(stroke
				(width 0.1)
				(type default)
			)
			(layer "F.Fab")
		)
		(fp_line
			(start 1.1938 -0.406654)
			(end 1.1938 0.4064)
			(stroke
				(width 0.1)
				(type default)
			)
			(layer "F.Fab")
		)
		(fp_line
			(start 1.1938 0.4064)
			(end 0.9144 0.4064)
			(stroke
				(width 0.1)
				(type default)
			)
			(layer "F.Fab")
		)
		(pad "1" smd rect
			(at -0.7366 0 270)
			(size 0.7112 0.8128)
			(layers "F.Cu" "F.Mask" "F.Paste")
			(net "P3V3_MAX11617_VDD")
		)
		(pad "2" smd rect
			(at 0.7366 0 270)
			(size 0.7112 0.8128)
			(layers "F.Cu" "F.Mask" "F.Paste")
			(net "P3V3_AUX")
		)
	)
	(footprint ""
		(layer "F.Cu")
		(at 283.112718 -388.71652 90)
		(property "Reference" "R6231"
			(at 0 0 90)
			(layer "F.SilkS")
			(hide yes)
			(effects
				(font
					(size 1.27 1.27)
				)
			)
		)
		(property "Value" ""
			(at 0 0 90)
			(layer "F.Fab")
			(effects
				(font
					(size 1.27 1.27)
				)
			)
		)
		(duplicate_pad_numbers_are_jumpers no)
		(fp_line
			(start 0.7874 -0.4064)
			(end 0.7874 0.4064)
			(stroke
				(width 0.1524)
				(type default)
			)
			(layer "F.SilkS")
		)
		(fp_line
			(start -0.7874 -0.4064)
			(end 0.7874 -0.4064)
			(stroke
				(width 0.1524)
				(type default)
			)
			(layer "F.SilkS")
		)
		(fp_line
			(start 0.7874 0.4064)
			(end -0.7874 0.4064)
			(stroke
				(width 0.1524)
				(type default)
			)
			(layer "F.SilkS")
		)
		(fp_line
			(start -0.7874 0.4064)
			(end -0.7874 -0.4064)
			(stroke
				(width 0.1524)
				(type default)
			)
			(layer "F.SilkS")
		)
		(fp_line
			(start -0.12065 -0.305054)
			(end -0.12065 -0.2794)
			(stroke
				(width 0.1)
				(type default)
			)
			(layer "F.Fab")
		)
		(fp_line
			(start -0.67945 -0.305054)
			(end -0.12065 -0.305054)
			(stroke
				(width 0.1)
				(type default)
			)
			(layer "F.Fab")
		)
		(fp_line
			(start 0.67945 -0.3048)
			(end 0.67945 0.3048)
			(stroke
				(width 0.1)
				(type default)
			)
			(layer "F.Fab")
		)
		(fp_line
			(start 0.12065 -0.3048)
			(end 0.67945 -0.3048)
			(stroke
				(width 0.1)
				(type default)
			)
			(layer "F.Fab")
		)
		(fp_line
			(start 0.12065 -0.2794)
			(end 0.12065 -0.3048)
			(stroke
				(width 0.1)
				(type default)
			)
			(layer "F.Fab")
		)
		(fp_line
			(start -0.12065 -0.2794)
			(end 0.12065 -0.2794)
			(stroke
				(width 0.1)
				(type default)
			)
			(layer "F.Fab")
		)
		(fp_line
			(start 0.120396 0.2794)
			(end -0.12065 0.2794)
			(stroke
				(width 0.1)
				(type default)
			)
			(layer "F.Fab")
		)
		(fp_line
			(start -0.12065 0.2794)
			(end -0.12065 0.3048)
			(stroke
				(width 0.1)
				(type default)
			)
			(layer "F.Fab")
		)
		(fp_line
			(start 0.67945 0.3048)
			(end 0.120396 0.3048)
			(stroke
				(width 0.1)
				(type default)
			)
			(layer "F.Fab")
		)
		(fp_line
			(start 0.120396 0.3048)
			(end 0.120396 0.2794)
			(stroke
				(width 0.1)
				(type default)
			)
			(layer "F.Fab")
		)
		(fp_line
			(start -0.12065 0.3048)
			(end -0.67945 0.3048)
			(stroke
				(width 0.1)
				(type default)
			)
			(layer "F.Fab")
		)
		(fp_line
			(start -0.67945 0.3048)
			(end -0.67945 -0.305054)
			(stroke
				(width 0.1)
				(type default)
			)
			(layer "F.Fab")
		)
		(pad "1" smd circle
			(at -0.40005 0 90)
			(size 0 0)
			(layers "F.Cu" "F.Mask" "F.Paste")
			(net "P3V3_AUX")
		)
		(pad "2" smd circle
			(at 0.40005 0 90)
			(size 0 0)
			(layers "F.Cu" "F.Mask" "F.Paste")
			(net "SMB_P12V_HSC_SCL")
		)
	)
	(footprint ""
		(layer "F.Cu")
		(at 227.7745 -402.191982 90)
		(property "Reference" "PC2223"
			(at 0 0 90)
			(layer "F.SilkS")
			(hide yes)
			(effects
				(font
					(size 1.27 1.27)
				)
			)
		)
		(property "Value" ""
			(at 0 0 90)
			(layer "F.Fab")
			(effects
				(font
					(size 1.27 1.27)
				)
			)
		)
		(duplicate_pad_numbers_are_jumpers no)
		(fp_line
			(start 0.7874 -0.4064)
			(end 0.7874 0.4064)
			(stroke
				(width 0.1524)
				(type default)
			)
			(layer "F.SilkS")
		)
		(fp_line
			(start -0.7874 -0.4064)
			(end 0.7874 -0.4064)
			(stroke
				(width 0.1524)
				(type default)
			)
			(layer "F.SilkS")
		)
		(fp_line
			(start 0.7874 0.4064)
			(end -0.7874 0.4064)
			(stroke
				(width 0.1524)
				(type default)
			)
			(layer "F.SilkS")
		)
		(fp_line
			(start -0.7874 0.4064)
			(end -0.7874 -0.4064)
			(stroke
				(width 0.1524)
				(type default)
			)
			(layer "F.SilkS")
		)
		(fp_line
			(start -0.12065 -0.305054)
			(end -0.12065 -0.2794)
			(stroke
				(width 0.1)
				(type default)
			)
			(layer "F.Fab")
		)
		(fp_line
			(start -0.67945 -0.305054)
			(end -0.12065 -0.305054)
			(stroke
				(width 0.1)
				(type default)
			)
			(layer "F.Fab")
		)
		(fp_line
			(start 0.67945 -0.3048)
			(end 0.67945 0.3048)
			(stroke
				(width 0.1)
				(type default)
			)
			(layer "F.Fab")
		)
		(fp_line
			(start 0.12065 -0.3048)
			(end 0.67945 -0.3048)
			(stroke
				(width 0.1)
				(type default)
			)
			(layer "F.Fab")
		)
		(fp_line
			(start 0.12065 -0.2794)
			(end 0.12065 -0.3048)
			(stroke
				(width 0.1)
				(type default)
			)
			(layer "F.Fab")
		)
		(fp_line
			(start -0.12065 -0.2794)
			(end 0.12065 -0.2794)
			(stroke
				(width 0.1)
				(type default)
			)
			(layer "F.Fab")
		)
		(fp_line
			(start 0.120396 0.2794)
			(end -0.12065 0.2794)
			(stroke
				(width 0.1)
				(type default)
			)
			(layer "F.Fab")
		)
		(fp_line
			(start -0.12065 0.2794)
			(end -0.12065 0.3048)
			(stroke
				(width 0.1)
				(type default)
			)
			(layer "F.Fab")
		)
		(fp_line
			(start 0.67945 0.3048)
			(end 0.120396 0.3048)
			(stroke
				(width 0.1)
				(type default)
			)
			(layer "F.Fab")
		)
		(fp_line
			(start 0.120396 0.3048)
			(end 0.120396 0.2794)
			(stroke
				(width 0.1)
				(type default)
			)
			(layer "F.Fab")
		)
		(fp_line
			(start -0.12065 0.3048)
			(end -0.67945 0.3048)
			(stroke
				(width 0.1)
				(type default)
			)
			(layer "F.Fab")
		)
		(fp_line
			(start -0.67945 0.3048)
			(end -0.67945 -0.305054)
			(stroke
				(width 0.1)
				(type default)
			)
			(layer "F.Fab")
		)
		(pad "1" smd circle
			(at -0.40005 0 90)
			(size 0 0)
			(layers "F.Cu" "F.Mask" "F.Paste")
			(net "HSC_VDD_R_4")
		)
		(pad "2" smd circle
			(at 0.40005 0 90)
			(size 0 0)
			(layers "F.Cu" "F.Mask" "F.Paste")
			(net "AGND_HSC")
		)
	)
	(footprint ""
		(layer "F.Cu")
		(at 142.748 -114.554)
		(property "Reference" "C8020"
			(at 0 0 0)
			(layer "F.SilkS")
			(hide yes)
			(effects
				(font
					(size 1.27 1.27)
				)
			)
		)
		(property "Value" ""
			(at 0 0 0)
			(layer "F.Fab")
			(effects
				(font
					(size 1.27 1.27)
				)
			)
		)
		(duplicate_pad_numbers_are_jumpers no)
		(fp_line
			(start -0.7874 -0.4064)
			(end 0.7874 -0.4064)
			(stroke
				(width 0.1524)
				(type default)
			)
			(layer "F.SilkS")
		)
		(fp_line
			(start -0.7874 0.4064)
			(end -0.7874 -0.4064)
			(stroke
				(width 0.1524)
				(type default)
			)
			(layer "F.SilkS")
		)
		(fp_line
			(start 0.7874 -0.4064)
			(end 0.7874 0.4064)
			(stroke
				(width 0.1524)
				(type default)
			)
			(layer "F.SilkS")
		)
		(fp_line
			(start 0.7874 0.4064)
			(end -0.7874 0.4064)
			(stroke
				(width 0.1524)
				(type default)
			)
			(layer "F.SilkS")
		)
		(fp_line
			(start -0.67945 -0.305054)
			(end -0.12065 -0.305054)
			(stroke
				(width 0.1)
				(type default)
			)
			(layer "F.Fab")
		)
		(fp_line
			(start -0.67945 0.3048)
			(end -0.67945 -0.305054)
			(stroke
				(width 0.1)
				(type default)
			)
			(layer "F.Fab")
		)
		(fp_line
			(start -0.12065 -0.305054)
			(end -0.12065 -0.2794)
			(stroke
				(width 0.1)
				(type default)
			)
			(layer "F.Fab")
		)
		(fp_line
			(start -0.12065 -0.2794)
			(end 0.12065 -0.2794)
			(stroke
				(width 0.1)
				(type default)
			)
			(layer "F.Fab")
		)
		(fp_line
			(start -0.12065 0.2794)
			(end -0.12065 0.3048)
			(stroke
				(width 0.1)
				(type default)
			)
			(layer "F.Fab")
		)
		(fp_line
			(start -0.12065 0.3048)
			(end -0.67945 0.3048)
			(stroke
				(width 0.1)
				(type default)
			)
			(layer "F.Fab")
		)
		(fp_line
			(start 0.120396 0.2794)
			(end -0.12065 0.2794)
			(stroke
				(width 0.1)
				(type default)
			)
			(layer "F.Fab")
		)
		(fp_line
			(start 0.120396 0.3048)
			(end 0.120396 0.2794)
			(stroke
				(width 0.1)
				(type default)
			)
			(layer "F.Fab")
		)
		(fp_line
			(start 0.12065 -0.3048)
			(end 0.67945 -0.3048)
			(stroke
				(width 0.1)
				(type default)
			)
			(layer "F.Fab")
		)
		(fp_line
			(start 0.12065 -0.2794)
			(end 0.12065 -0.3048)
			(stroke
				(width 0.1)
				(type default)
			)
			(layer "F.Fab")
		)
		(fp_line
			(start 0.67945 -0.3048)
			(end 0.67945 0.3048)
			(stroke
				(width 0.1)
				(type default)
			)
			(layer "F.Fab")
		)
		(fp_line
			(start 0.67945 0.3048)
			(end 0.120396 0.3048)
			(stroke
				(width 0.1)
				(type default)
			)
			(layer "F.Fab")
		)
		(pad "1" smd circle
			(at -0.40005 0)
			(size 0 0)
			(layers "F.Cu" "F.Mask" "F.Paste")
			(net "UV_P2V5_COMP")
		)
		(pad "2" smd circle
			(at 0.40005 0)
			(size 0 0)
			(layers "F.Cu" "F.Mask" "F.Paste")
			(net "GND")
		)
	)
	(footprint ""
		(layer "F.Cu")
		(at 151.13 -114.173 180)
		(property "Reference" "R1338"
			(at 0 0 180)
			(layer "F.SilkS")
			(hide yes)
			(effects
				(font
					(size 1.27 1.27)
				)
			)
		)
		(property "Value" ""
			(at 0 0 180)
			(layer "F.Fab")
			(effects
				(font
					(size 1.27 1.27)
				)
			)
		)
		(duplicate_pad_numbers_are_jumpers no)
		(fp_line
			(start 0.7874 0.4064)
			(end -0.7874 0.4064)
			(stroke
				(width 0.1524)
				(type default)
			)
			(layer "F.SilkS")
		)
		(fp_line
			(start 0.7874 -0.4064)
			(end 0.7874 0.4064)
			(stroke
				(width 0.1524)
				(type default)
			)
			(layer "F.SilkS")
		)
		(fp_line
			(start -0.7874 0.4064)
			(end -0.7874 -0.4064)
			(stroke
				(width 0.1524)
				(type default)
			)
			(layer "F.SilkS")
		)
		(fp_line
			(start -0.7874 -0.4064)
			(end 0.7874 -0.4064)
			(stroke
				(width 0.1524)
				(type default)
			)
			(layer "F.SilkS")
		)
		(fp_line
			(start 0.67945 0.3048)
			(end 0.120396 0.3048)
			(stroke
				(width 0.1)
				(type default)
			)
			(layer "F.Fab")
		)
		(fp_line
			(start 0.67945 -0.3048)
			(end 0.67945 0.3048)
			(stroke
				(width 0.1)
				(type default)
			)
			(layer "F.Fab")
		)
		(fp_line
			(start 0.12065 -0.2794)
			(end 0.12065 -0.3048)
			(stroke
				(width 0.1)
				(type default)
			)
			(layer "F.Fab")
		)
		(fp_line
			(start 0.12065 -0.3048)
			(end 0.67945 -0.3048)
			(stroke
				(width 0.1)
				(type default)
			)
			(layer "F.Fab")
		)
		(fp_line
			(start 0.120396 0.3048)
			(end 0.120396 0.2794)
			(stroke
				(width 0.1)
				(type default)
			)
			(layer "F.Fab")
		)
		(fp_line
			(start 0.120396 0.2794)
			(end -0.12065 0.2794)
			(stroke
				(width 0.1)
				(type default)
			)
			(layer "F.Fab")
		)
		(fp_line
			(start -0.12065 0.3048)
			(end -0.67945 0.3048)
			(stroke
				(width 0.1)
				(type default)
			)
			(layer "F.Fab")
		)
		(fp_line
			(start -0.12065 0.2794)
			(end -0.12065 0.3048)
			(stroke
				(width 0.1)
				(type default)
			)
			(layer "F.Fab")
		)
		(fp_line
			(start -0.12065 -0.2794)
			(end 0.12065 -0.2794)
			(stroke
				(width 0.1)
				(type default)
			)
			(layer "F.Fab")
		)
		(fp_line
			(start -0.12065 -0.305054)
			(end -0.12065 -0.2794)
			(stroke
				(width 0.1)
				(type default)
			)
			(layer "F.Fab")
		)
		(fp_line
			(start -0.67945 0.3048)
			(end -0.67945 -0.305054)
			(stroke
				(width 0.1)
				(type default)
			)
			(layer "F.Fab")
		)
		(fp_line
			(start -0.67945 -0.305054)
			(end -0.12065 -0.305054)
			(stroke
				(width 0.1)
				(type default)
			)
			(layer "F.Fab")
		)
		(pad "1" smd circle
			(at -0.40005 0 180)
			(size 0 0)
			(layers "F.Cu" "F.Mask" "F.Paste")
			(net "P3V3_AUX")
		)
		(pad "2" smd circle
			(at 0.40005 0 180)
			(size 0 0)
			(layers "F.Cu" "F.Mask" "F.Paste")
			(net "SCM_IRQ_N")
		)
	)
	(footprint ""
		(layer "F.Cu")
		(at 69.098668 -382.951228)
		(property "Reference" "ME10"
			(at 0 0 0)
			(layer "F.SilkS")
			(hide yes)
			(effects
				(font
					(size 1.27 1.27)
				)
			)
		)
		(property "Value" ""
			(at 0 0 0)
			(layer "F.Fab")
			(effects
				(font
					(size 1.27 1.27)
				)
			)
		)
		(duplicate_pad_numbers_are_jumpers no)
	)
)
